(kicad_pcb
	(version 20260206)
	(generator "pcbnew")
	(generator_version "10.0")
	(general
		(thickness 1.6)
		(legacy_teardrops no)
	)
	(paper "A4")
	(title_block
		(title "baseboard — 13948-1b.1110WZS1818.brd")
		(comment 1 "Honey Badger (Wiwynn) / footprints 1373-1377 of 2523")
	)
	(layers
		(0 "F.Cu" signal "TOP")
		(4 "In1.Cu" signal "L2GND")
		(6 "In2.Cu" signal "L3")
		(8 "In3.Cu" signal "L4VCC")
		(10 "In4.Cu" signal "L5VCC")
		(12 "In5.Cu" signal "L6")
		(14 "In6.Cu" signal "L7GND")
		(2 "B.Cu" signal "BOTTOM")
		(9 "F.Adhes" user "F.Adhesive")
		(11 "B.Adhes" user "B.Adhesive")
		(13 "F.Paste" user "Package Geometry/Pastemask Top")
		(15 "B.Paste" user "Package Geometry/Pastemask Bottom")
		(5 "F.SilkS" user "Ref Des/Silkscreen Top")
		(7 "B.SilkS" user "Ref Des/Silkscreen Bottom")
		(1 "F.Mask" user "Board Geometry/Soldermask Top")
		(3 "B.Mask" user "Board Geometry/Soldermask Bottom")
		(17 "Dwgs.User" user "User.Drawings")
		(19 "Cmts.User" user "User.Comments")
		(21 "Eco1.User" user "User.Eco1")
		(23 "Eco2.User" user "User.Eco2")
		(25 "Edge.Cuts" user "Board Geometry/Outline")
		(27 "Margin" user)
		(31 "F.CrtYd" user "Package Geometry/Place Bound Top")
		(29 "B.CrtYd" user "Package Geometry/Place Bound Bottom")
		(35 "F.Fab" user "Ref Des/Assembly Top")
		(33 "B.Fab" user "Ref Des/Assembly Bottom")
	)
	(footprint ""
		(layer "F.Cu")
		(at 39.0652 -118.1862 -90)
		(property "Reference" "SC1301"
			(at 0 0 270)
			(layer "F.SilkS")
			(hide yes)
			(effects
				(font
					(size 1.27 1.27)
				)
			)
		)
		(property "Value" "SCD1U16V2KX-3GP"
			(at 1.1811 -2.7051 270)
			(unlocked yes)
			(layer "F.Fab")
			(hide yes)
			(effects
				(font
					(size 1.016 1.016)
					(thickness 0.1524)
				)
			)
		)
		(property "Device Type" "C402H22"
			(at 1.1811 -4.2291 270)
			(unlocked yes)
			(layer "F.Fab")
			(hide yes)
			(effects
				(font
					(size 1.016 1.016)
					(thickness 0.1524)
				)
			)
		)
		(duplicate_pad_numbers_are_jumpers no)
		(fp_rect
			(start -0.4318 0.9525)
			(end 0.4318 -0.9525)
			(stroke
				(width 0)
				(type default)
			)
			(fill no)
			(layer "F.CrtYd")
		)
		(fp_rect
			(start -0.4318 0.9525)
			(end 0.4318 -0.9525)
			(stroke
				(width 0)
				(type default)
			)
			(fill no)
			(layer "F.Fab")
		)
		(pad "1" smd custom
			(at 0 -0.4445 270)
			(size 0.1524 0.1524)
			(layers "F.Cu" "F.Mask" "F.Paste")
			(net "P3V3_STBY")
			(options
				(clearance outline)
				(anchor circle)
			)
			(primitives
				(gr_poly
					(pts
						(arc
							(start 0.3048 -0.2032)
							(mid 0.275042 -0.275042)
							(end 0.2032 -0.3048)
						)
						(arc
							(start -0.2032 -0.3048)
							(mid -0.275042 -0.275042)
							(end -0.3048 -0.2032)
						)
						(arc
							(start -0.3048 0.2032)
							(mid -0.275042 0.275042)
							(end -0.2032 0.3048)
						)
						(arc
							(start 0.2032 0.3048)
							(mid 0.275042 0.275042)
							(end 0.3048 0.2032)
						)
					)
					(width 0)
					(fill yes)
				)
			)
		)
		(pad "2" smd custom
			(at 0 0.4445 270)
			(size 0.1524 0.1524)
			(layers "F.Cu" "F.Mask" "F.Paste")
			(net "GND")
			(options
				(clearance outline)
				(anchor circle)
			)
			(primitives
				(gr_poly
					(pts
						(arc
							(start 0.3048 -0.2032)
							(mid 0.275042 -0.275042)
							(end 0.2032 -0.3048)
						)
						(arc
							(start -0.2032 -0.3048)
							(mid -0.275042 -0.275042)
							(end -0.3048 -0.2032)
						)
						(arc
							(start -0.3048 0.2032)
							(mid -0.275042 0.275042)
							(end -0.2032 0.3048)
						)
						(arc
							(start 0.2032 0.3048)
							(mid 0.275042 0.275042)
							(end 0.3048 0.2032)
						)
					)
					(width 0)
					(fill yes)
				)
			)
		)
	)
	(footprint ""
		(layer "F.Cu")
		(at 318.008 -161.29 -90)
		(property "Reference" "R310"
			(at 0 0 270)
			(layer "F.SilkS")
			(hide yes)
			(effects
				(font
					(size 1.27 1.27)
				)
			)
		)
		(property "Value" "10KR2F-2-GP"
			(at 0.064008 -3.993896 270)
			(unlocked yes)
			(layer "F.Fab")
			(hide yes)
			(effects
				(font
					(size 1.016 1.016)
					(thickness 0.1524)
				)
			)
		)
		(property "Device Type" "R402H16"
			(at 0.064008 -5.517896 270)
			(unlocked yes)
			(layer "F.Fab")
			(hide yes)
			(effects
				(font
					(size 1.016 1.016)
					(thickness 0.1524)
				)
			)
		)
		(duplicate_pad_numbers_are_jumpers no)
		(fp_line
			(start -0.508 -0.9398)
			(end -0.508 0.9398)
			(stroke
				(width 0.1524)
				(type default)
			)
			(layer "F.SilkS")
		)
		(fp_line
			(start 0.508 -0.9398)
			(end -0.508 -0.9398)
			(stroke
				(width 0.1524)
				(type default)
			)
			(layer "F.SilkS")
		)
		(fp_rect
			(start -0.508 0.9398)
			(end 0.508 -0.9398)
			(stroke
				(width 0)
				(type default)
			)
			(fill no)
			(layer "F.CrtYd")
		)
		(fp_rect
			(start -0.508 0.9398)
			(end 0.508 -0.9398)
			(stroke
				(width 0)
				(type default)
			)
			(fill no)
			(layer "F.Fab")
		)
		(pad "1" smd custom
			(at 0 -0.4445 270)
			(size 0.1397 0.1397)
			(layers "F.Cu" "F.Mask" "F.Paste")
			(net "P3V3_STBY")
			(options
				(clearance outline)
				(anchor circle)
			)
			(primitives
				(gr_poly
					(pts
						(arc
							(start -0.1778 -0.2794)
							(mid -0.249642 -0.249642)
							(end -0.2794 -0.1778)
						)
						(arc
							(start -0.2794 0.1778)
							(mid -0.249642 0.249642)
							(end -0.1778 0.2794)
						)
						(arc
							(start 0.1778 0.2794)
							(mid 0.249642 0.249642)
							(end 0.2794 0.1778)
						)
						(arc
							(start 0.2794 -0.1778)
							(mid 0.249642 -0.249642)
							(end 0.1778 -0.2794)
						)
					)
					(width 0)
					(fill yes)
				)
			)
		)
		(pad "2" smd custom
			(at 0 0.4445 270)
			(size 0.1397 0.1397)
			(layers "F.Cu" "F.Mask" "F.Paste")
			(net "PU_BMC0_SCL13")
			(options
				(clearance outline)
				(anchor circle)
			)
			(primitives
				(gr_poly
					(pts
						(arc
							(start -0.1778 -0.2794)
							(mid -0.249642 -0.249642)
							(end -0.2794 -0.1778)
						)
						(arc
							(start -0.2794 0.1778)
							(mid -0.249642 0.249642)
							(end -0.1778 0.2794)
						)
						(arc
							(start 0.1778 0.2794)
							(mid 0.249642 0.249642)
							(end 0.2794 0.1778)
						)
						(arc
							(start 0.2794 -0.1778)
							(mid 0.249642 -0.249642)
							(end 0.1778 -0.2794)
						)
					)
					(width 0)
					(fill yes)
				)
			)
		)
	)
	(footprint ""
		(layer "F.Cu")
		(at 283.582872 -221.052136)
		(property "Reference" "PU5"
			(at 0 0 0)
			(layer "F.SilkS")
			(hide yes)
			(effects
				(font
					(size 1.27 1.27)
				)
			)
		)
		(property "Value" "TPS74801RGW-GP"
			(at -4.7244 -6.223 0)
			(unlocked yes)
			(layer "F.Fab")
			(hide yes)
			(effects
				(font
					(size 1.016 1.016)
					(thickness 0.1524)
				)
			)
		)
		(property "Device Type" "QFN20-1G3D15H40"
			(at -4.7244 -7.747 0)
			(unlocked yes)
			(layer "F.Fab")
			(hide yes)
			(effects
				(font
					(size 1.016 1.016)
					(thickness 0.1524)
				)
			)
		)
		(duplicate_pad_numbers_are_jumpers no)
		(fp_line
			(start -3.5179 -3.5179)
			(end -3.5179 -2.2479)
			(stroke
				(width 0.1524)
				(type default)
			)
			(layer "F.SilkS")
		)
		(fp_line
			(start -3.5179 2.2479)
			(end -3.5179 3.5179)
			(stroke
				(width 0.1524)
				(type default)
			)
			(layer "F.SilkS")
		)
		(fp_line
			(start -3.5179 3.5179)
			(end -2.2479 3.5179)
			(stroke
				(width 0.1524)
				(type default)
			)
			(layer "F.SilkS")
		)
		(fp_line
			(start -3.160522 1.299972)
			(end -3.922522 1.299972)
			(stroke
				(width 0.1524)
				(type default)
			)
			(layer "F.SilkS")
		)
		(fp_line
			(start -2.2479 -3.5179)
			(end -3.5179 -3.5179)
			(stroke
				(width 0.1524)
				(type default)
			)
			(layer "F.SilkS")
		)
		(fp_line
			(start -1.299972 -3.160522)
			(end -1.299972 -3.668522)
			(stroke
				(width 0.1524)
				(type default)
			)
			(layer "F.SilkS")
		)
		(fp_line
			(start 1.299972 3.160522)
			(end 1.299972 3.668522)
			(stroke
				(width 0.1524)
				(type default)
			)
			(layer "F.SilkS")
		)
		(fp_line
			(start 2.2479 3.5179)
			(end 3.5179 3.5179)
			(stroke
				(width 0.1524)
				(type default)
			)
			(layer "F.SilkS")
		)
		(fp_line
			(start 3.160522 -1.299972)
			(end 3.922522 -1.299972)
			(stroke
				(width 0.1524)
				(type default)
			)
			(layer "F.SilkS")
		)
		(fp_line
			(start 3.5179 3.5179)
			(end 3.5179 2.2479)
			(stroke
				(width 0.1524)
				(type default)
			)
			(layer "F.SilkS")
		)
		(fp_poly
			(pts
				(xy 3.5179 -3.5179) (xy 2.2479 -3.5179) (xy 3.5179 -2.2479)
			)
			(stroke
				(width 0)
				(type default)
			)
			(fill yes)
			(layer "F.SilkS")
		)
		(fp_rect
			(start -2.5019 2.5019)
			(end 2.5019 -2.5019)
			(stroke
				(width 0)
				(type default)
			)
			(fill no)
			(layer "F.CrtYd")
		)
		(fp_poly
			(pts
				(xy -3.5179 3.5179) (xy -3.5179 -3.5179) (xy 3.5179 -3.5179) (xy 3.5179 -2.5019) (xy -2.5019 -2.5019)
				(xy -2.5019 2.5019) (xy 2.5019 2.5019) (xy 2.5019 -2.49682) (xy 3.5179 -2.49682) (xy 3.5179 3.5179)
			)
			(stroke
				(width 0)
				(type default)
			)
			(fill no)
			(layer "F.CrtYd")
		)
		(fp_rect
			(start -3.5179 3.5179)
			(end 3.5179 -3.5179)
			(stroke
				(width 0)
				(type default)
			)
			(fill no)
			(layer "F.Fab")
		)
		(pad "1" smd rect
			(at 1.299972 -2.474722)
			(size 0.3556 1.0668)
			(layers "F.Cu" "F.Mask" "F.Paste")
			(net "TPS74801_1V53_STBY_OUT")
		)
		(pad "2" smd rect
			(at 0.649986 -2.474722)
			(size 0.3556 1.0668)
			(layers "F.Cu" "F.Mask" "F.Paste")
			(net "GND")
		)
		(pad "3" smd rect
			(at 0 -2.474722)
			(size 0.3556 1.0668)
			(layers "F.Cu" "F.Mask" "F.Paste")
			(net "GND")
		)
		(pad "4" smd rect
			(at -0.649986 -2.474722)
			(size 0.3556 1.0668)
			(layers "F.Cu" "F.Mask" "F.Paste")
			(net "GND")
		)
		(pad "5" smd rect
			(at -1.299972 -2.474722)
			(size 0.3556 1.0668)
			(layers "F.Cu" "F.Mask" "F.Paste")
			(net "TPS74801_P1V53_STBY_IN")
		)
		(pad "6" smd rect
			(at -2.474722 -1.299972)
			(size 1.0668 0.3556)
			(layers "F.Cu" "F.Mask" "F.Paste")
			(net "TPS74801_P1V53_STBY_IN")
		)
		(pad "7" smd rect
			(at -2.474722 -0.649986)
			(size 1.0668 0.3556)
			(layers "F.Cu" "F.Mask" "F.Paste")
			(net "TPS74801_P1V53_STBY_IN")
		)
		(pad "8" smd rect
			(at -2.474722 0)
			(size 1.0668 0.3556)
			(layers "F.Cu" "F.Mask" "F.Paste")
			(net "TPS74801_P1V53_STBY_IN")
		)
		(pad "9" smd rect
			(at -2.474722 0.649986)
			(size 1.0668 0.3556)
			(layers "F.Cu" "F.Mask" "F.Paste")
			(net "P1V53_STBY_PG")
		)
		(pad "10" smd rect
			(at -2.474722 1.299972)
			(size 1.0668 0.3556)
			(layers "F.Cu" "F.Mask" "F.Paste")
			(net "TPS74801_1V53_STBY_BIAS")
		)
		(pad "11" smd rect
			(at -1.299972 2.474722)
			(size 0.3556 1.0668)
			(layers "F.Cu" "F.Mask" "F.Paste")
			(net "TPS74801_1V53_STBY_EN")
		)
		(pad "12" smd rect
			(at -0.649986 2.474722)
			(size 0.3556 1.0668)
			(layers "F.Cu" "F.Mask" "F.Paste")
			(net "GND")
		)
		(pad "13" smd rect
			(at 0 2.474722)
			(size 0.3556 1.0668)
			(layers "F.Cu" "F.Mask" "F.Paste")
			(net "GND")
		)
		(pad "14" smd rect
			(at 0.649986 2.474722)
			(size 0.3556 1.0668)
			(layers "F.Cu" "F.Mask" "F.Paste")
			(net "GND")
		)
		(pad "15" smd rect
			(at 1.299972 2.474722)
			(size 0.3556 1.0668)
			(layers "F.Cu" "F.Mask" "F.Paste")
			(net "TPS74801_1V53_STBY_SS")
		)
		(pad "16" smd rect
			(at 2.474722 1.299972)
			(size 1.0668 0.3556)
			(layers "F.Cu" "F.Mask" "F.Paste")
			(net "TPS74801_1V53_STBY_FB")
		)
		(pad "17" smd rect
			(at 2.474722 0.649986)
			(size 1.0668 0.3556)
			(layers "F.Cu" "F.Mask" "F.Paste")
			(net "GND")
		)
		(pad "18" smd rect
			(at 2.474722 0)
			(size 1.0668 0.3556)
			(layers "F.Cu" "F.Mask" "F.Paste")
			(net "TPS74801_1V53_STBY_OUT")
		)
		(pad "19" smd rect
			(at 2.474722 -0.649986)
			(size 1.0668 0.3556)
			(layers "F.Cu" "F.Mask" "F.Paste")
			(net "TPS74801_1V53_STBY_OUT")
		)
		(pad "20" smd rect
			(at 2.474722 -1.299972)
			(size 1.0668 0.3556)
			(layers "F.Cu" "F.Mask" "F.Paste")
			(net "TPS74801_1V53_STBY_OUT")
		)
		(pad "21" smd rect
			(at 0 0)
			(size 3.2512 3.2512)
			(layers "F.Cu" "F.Mask" "F.Paste")
			(net "GND")
		)
	)
	(footprint ""
		(layer "F.Cu")
		(at 199.898 -227.838 90)
		(property "Reference" "C370"
			(at 0 0 90)
			(layer "F.SilkS")
			(hide yes)
			(effects
				(font
					(size 1.27 1.27)
				)
			)
		)
		(property "Value" "SC1U6D3V3KX-2GP"
			(at 0 -2.8194 90)
			(unlocked yes)
			(layer "F.Fab")
			(hide yes)
			(effects
				(font
					(size 1.016 1.016)
					(thickness 0.1524)
				)
			)
		)
		(property "Device Type" "C603H36"
			(at 0 -4.3434 90)
			(unlocked yes)
			(layer "F.Fab")
			(hide yes)
			(effects
				(font
					(size 1.016 1.016)
					(thickness 0.1524)
				)
			)
		)
		(duplicate_pad_numbers_are_jumpers no)
		(fp_line
			(start 0.508 0)
			(end -0.508 0)
			(stroke
				(width 0.2032)
				(type default)
			)
			(layer "F.SilkS")
		)
		(fp_rect
			(start -0.5842 1.3335)
			(end 0.5842 -1.3335)
			(stroke
				(width 0)
				(type default)
			)
			(fill no)
			(layer "F.CrtYd")
		)
		(fp_rect
			(start -0.5842 1.3335)
			(end 0.5842 -1.3335)
			(stroke
				(width 0)
				(type default)
			)
			(fill no)
			(layer "F.Fab")
		)
		(pad "1" smd custom
			(at 0 -0.762 90)
			(size 0.2159 0.2159)
			(layers "F.Cu" "F.Mask" "F.Paste")
			(net "P3V3_STBY")
			(options
				(clearance outline)
				(anchor circle)
			)
			(primitives
				(gr_poly
					(pts
						(arc
							(start -0.3302 -0.4318)
							(mid -0.402042 -0.402042)
							(end -0.4318 -0.3302)
						)
						(arc
							(start -0.4318 0.3302)
							(mid -0.402042 0.402042)
							(end -0.3302 0.4318)
						)
						(arc
							(start 0.3302 0.4318)
							(mid 0.402042 0.402042)
							(end 0.4318 0.3302)
						)
						(arc
							(start 0.4318 -0.3302)
							(mid 0.402042 -0.402042)
							(end 0.3302 -0.4318)
						)
					)
					(width 0)
					(fill yes)
				)
			)
		)
		(pad "2" smd custom
			(at 0 0.762 90)
			(size 0.2159 0.2159)
			(layers "F.Cu" "F.Mask" "F.Paste")
			(net "GND")
			(options
				(clearance outline)
				(anchor circle)
			)
			(primitives
				(gr_poly
					(pts
						(arc
							(start -0.3302 -0.4318)
							(mid -0.402042 -0.402042)
							(end -0.4318 -0.3302)
						)
						(arc
							(start -0.4318 0.3302)
							(mid -0.402042 0.402042)
							(end -0.3302 0.4318)
						)
						(arc
							(start 0.3302 0.4318)
							(mid 0.402042 0.402042)
							(end 0.4318 0.3302)
						)
						(arc
							(start 0.4318 -0.3302)
							(mid 0.402042 -0.402042)
							(end 0.3302 -0.4318)
						)
					)
					(width 0)
					(fill yes)
				)
			)
		)
	)
	(footprint ""
		(layer "F.Cu")
		(at 80.118966 -67.564 180)
		(property "Reference" "SC984"
			(at 0 0 180)
			(layer "F.SilkS")
			(hide yes)
			(effects
				(font
					(size 1.27 1.27)
				)
			)
		)
		(property "Value" "SCD1U16V2KX-3GP"
			(at 1.1811 -2.7051 180)
			(unlocked yes)
			(layer "F.Fab")
			(hide yes)
			(effects
				(font
					(size 1.016 1.016)
					(thickness 0.1524)
				)
			)
		)
		(property "Device Type" "C402H22"
			(at 1.1811 -4.2291 180)
			(unlocked yes)
			(layer "F.Fab")
			(hide yes)
			(effects
				(font
					(size 1.016 1.016)
					(thickness 0.1524)
				)
			)
		)
		(duplicate_pad_numbers_are_jumpers no)
		(fp_rect
			(start -0.4318 0.9525)
			(end 0.4318 -0.9525)
			(stroke
				(width 0)
				(type default)
			)
			(fill no)
			(layer "F.CrtYd")
		)
		(fp_rect
			(start -0.4318 0.9525)
			(end 0.4318 -0.9525)
			(stroke
				(width 0)
				(type default)
			)
			(fill no)
			(layer "F.Fab")
		)
		(pad "1" smd custom
			(at 0 -0.4445 180)
			(size 0.1524 0.1524)
			(layers "F.Cu" "F.Mask" "F.Paste")
			(net "P1V8_C")
			(options
				(clearance outline)
				(anchor circle)
			)
			(primitives
				(gr_poly
					(pts
						(arc
							(start 0.3048 -0.2032)
							(mid 0.275042 -0.275042)
							(end 0.2032 -0.3048)
						)
						(arc
							(start -0.2032 -0.3048)
							(mid -0.275042 -0.275042)
							(end -0.3048 -0.2032)
						)
						(arc
							(start -0.3048 0.2032)
							(mid -0.275042 0.275042)
							(end -0.2032 0.3048)
						)
						(arc
							(start 0.2032 0.3048)
							(mid 0.275042 0.275042)
							(end 0.3048 0.2032)
						)
					)
					(width 0)
					(fill yes)
				)
			)
		)
		(pad "2" smd custom
			(at 0 0.4445 180)
			(size 0.1524 0.1524)
			(layers "F.Cu" "F.Mask" "F.Paste")
			(net "GND")
			(options
				(clearance outline)
				(anchor circle)
			)
			(primitives
				(gr_poly
					(pts
						(arc
							(start 0.3048 -0.2032)
							(mid 0.275042 -0.275042)
							(end 0.2032 -0.3048)
						)
						(arc
							(start -0.2032 -0.3048)
							(mid -0.275042 -0.275042)
							(end -0.3048 -0.2032)
						)
						(arc
							(start -0.3048 0.2032)
							(mid -0.275042 0.275042)
							(end -0.2032 0.3048)
						)
						(arc
							(start 0.2032 0.3048)
							(mid 0.275042 0.275042)
							(end 0.3048 0.2032)
						)
					)
					(width 0)
					(fill yes)
				)
			)
		)
	)
)
